(kicad_pcb
	(version 20241229)
	(generator "pcbnew")
	(generator_version "9.0")
	(general
		(thickness 1.63)
		(legacy_teardrops no)
	)
	(paper "A4")
	(title_block
		(title "CM4 Baseboard")
		(date "2026-01-05")
		(rev "1.1.1")
		(company "Antmicro Ltd")
		(comment 1 "www.antmicro.com")
		(comment 9 "footprints 252-255 of 506")
	)
	(layers
		(0 "F.Cu" signal)
		(4 "In1.Cu" power)
		(6 "In2.Cu" power)
		(8 "In3.Cu" signal)
		(10 "In4.Cu" signal)
		(2 "B.Cu" signal)
		(9 "F.Adhes" user "F.Adhesive")
		(11 "B.Adhes" user "B.Adhesive")
		(13 "F.Paste" user)
		(15 "B.Paste" user)
		(5 "F.SilkS" user "F.Silkscreen")
		(7 "B.SilkS" user "B.Silkscreen")
		(1 "F.Mask" user)
		(3 "B.Mask" user)
		(17 "Dwgs.User" user "User.Drawings")
		(19 "Cmts.User" user "User.Comments")
		(21 "Eco1.User" user "User.Eco1")
		(23 "Eco2.User" user "User.Eco2")
		(25 "Edge.Cuts" user)
		(27 "Margin" user)
		(31 "F.CrtYd" user "F.Courtyard")
		(29 "B.CrtYd" user "B.Courtyard")
		(35 "F.Fab" user)
		(33 "B.Fab" user)
	)
	(footprint "antmicro-footprints:LED_0603_1608Metric_G"
		(layer "F.Cu")
		(at 84.892962 120.7415 180)
		(descr "LED SMD 0603 Green")
		(tags "LED SMD 0603 Green")
		(property "Reference" "D906"
			(at -3.125 -1.4 0)
			(layer "F.SilkS")
			(effects
				(font
					(size 0.7 0.7)
					(thickness 0.15)
				)
				(justify right bottom)
			)
		)
		(property "Value" "LED_G_0603_KP-1608CGCK"
			(at -0.001 1.599 0)
			(layer "F.Fab")
			(effects
				(font
					(size 0.7 0.7)
					(thickness 0.15)
				)
				(justify right bottom)
			)
		)
		(property "Datasheet" "http://www.kingbright.com/attachments/file/psearch//000/00/00/KP-1608CGCK(Ver.23B).pdf"
			(at 0 0 180)
			(layer "F.Fab")
			(hide yes)
			(effects
				(font
					(size 1.27 1.27)
					(thickness 0.15)
				)
			)
		)
		(property "MPN" "KP-1608CGCK"
			(at 0 0 180)
			(unlocked yes)
			(layer "F.Fab")
			(hide yes)
			(effects
				(font
					(size 1 1)
					(thickness 0.15)
				)
			)
		)
		(property "Manufacturer" "Kingbright"
			(at 0 0 180)
			(unlocked yes)
			(layer "F.Fab")
			(hide yes)
			(effects
				(font
					(size 1 1)
					(thickness 0.15)
				)
			)
		)
		(property "Color" "Green"
			(at 0 0 180)
			(unlocked yes)
			(layer "F.Fab")
			(hide yes)
			(effects
				(font
					(size 1 1)
					(thickness 0.15)
				)
			)
		)
		(property "Author" "Antmicro"
			(at 0 0 180)
			(unlocked yes)
			(layer "F.Fab")
			(hide yes)
			(effects
				(font
					(size 1 1)
					(thickness 0.15)
				)
			)
		)
		(property "License" "Apache-2.0"
			(at 0 0 180)
			(unlocked yes)
			(layer "F.Fab")
			(hide yes)
			(effects
				(font
					(size 1 1)
					(thickness 0.15)
				)
			)
		)
		(sheetname "/USB/")
		(sheetfile "usb.kicad_sch")
		(attr smd)
		(fp_line
			(start 0.22 0.35)
			(end -0.22 0.35)
			(stroke
				(width 0.15)
				(type solid)
			)
			(layer "F.SilkS")
		)
		(fp_line
			(start 0.22 -0.35)
			(end -0.22 -0.35)
			(stroke
				(width 0.15)
				(type solid)
			)
			(layer "F.SilkS")
		)
		(fp_line
			(start 0.105328 0.201008)
			(end 0.105328 -0.198992)
			(stroke
				(width 0.1)
				(type solid)
			)
			(layer "F.SilkS")
		)
		(fp_line
			(start 0.105328 0.201008)
			(end -0.094672 0.001008)
			(stroke
				(width 0.1)
				(type solid)
			)
			(layer "F.SilkS")
		)
		(fp_line
			(start 0.105328 0.001008)
			(end 0.24 0.001)
			(stroke
				(width 0.1)
				(type solid)
			)
			(layer "F.SilkS")
		)
		(fp_line
			(start -0.094672 0.201008)
			(end -0.094672 -0.198992)
			(stroke
				(width 0.1)
				(type solid)
			)
			(layer "F.SilkS")
		)
		(fp_line
			(start -0.094672 0.001008)
			(end 0.105328 -0.198992)
			(stroke
				(width 0.1)
				(type solid)
			)
			(layer "F.SilkS")
		)
		(fp_line
			(start -0.094672 0.001008)
			(end -0.24 0.001008)
			(stroke
				(width 0.1)
				(type solid)
			)
			(layer "F.SilkS")
		)
		(fp_line
			(start -1.18 -0.319)
			(end -1.18 0.321)
			(stroke
				(width 0.15)
				(type solid)
			)
			(layer "F.SilkS")
		)
		(fp_rect
			(start 1.25 0.65)
			(end -1.25 -0.65)
			(stroke
				(width 0.05)
				(type solid)
			)
			(fill no)
			(layer "F.CrtYd")
		)
		(fp_line
			(start 0.599 0)
			(end 0.201 0)
			(stroke
				(width 0.15)
				(type solid)
			)
			(layer "F.Fab")
		)
		(fp_line
			(start 0.201 0.2)
			(end 0.201 0)
			(stroke
				(width 0.15)
				(type solid)
			)
			(layer "F.Fab")
		)
		(fp_line
			(start 0.201 0)
			(end 0.201 -0.202)
			(stroke
				(width 0.15)
				(type solid)
			)
			(layer "F.Fab")
		)
		(fp_line
			(start 0.201 -0.202)
			(end -0.101 0)
			(stroke
				(width 0.15)
				(type solid)
			)
			(layer "F.Fab")
		)
		(fp_line
			(start -0.101 0)
			(end 0.201 0.2)
			(stroke
				(width 0.15)
				(type solid)
			)
			(layer "F.Fab")
		)
		(fp_line
			(start -0.199 0.2)
			(end -0.199 0.1)
			(stroke
				(width 0.15)
				(type solid)
			)
			(layer "F.Fab")
		)
		(fp_line
			(start -0.199 0)
			(end -0.597 0)
			(stroke
				(width 0.15)
				(type solid)
			)
			(layer "F.Fab")
		)
		(fp_line
			(start -0.199 -0.202)
			(end -0.199 0.1)
			(stroke
				(width 0.15)
				(type solid)
			)
			(layer "F.Fab")
		)
		(fp_rect
			(start 0.848 0.4)
			(end -0.85 -0.402)
			(stroke
				(width 0.15)
				(type solid)
			)
			(fill no)
			(layer "F.Fab")
		)
		(fp_text user "Author: Antmicro"
			(at -1.4224 4.799 180)
			(layer "F.Fab")
			(effects
				(font
					(size 0.7 0.7)
					(thickness 0.15)
				)
				(justify left bottom)
			)
		)
		(fp_text user "${REFERENCE}"
			(at -1.4224 5.999 180)
			(layer "F.Fab")
			(effects
				(font
					(size 0.7 0.7)
					(thickness 0.15)
				)
				(justify left bottom)
			)
		)
		(fp_text user "License: Apache-2.0"
			(at -1.4224 3.599 180)
			(layer "F.Fab")
			(effects
				(font
					(size 0.7 0.7)
					(thickness 0.15)
				)
				(justify left bottom)
			)
		)
		(pad "1" smd roundrect
			(at -0.7 0)
			(size 0.8 1)
			(layers "F.Cu" "F.Mask" "F.Paste")
			(roundrect_rratio 0.2)
			(net 498 "Net-(D906-C)")
			(pinfunction "C")
			(pintype "passive")
		)
		(pad "2" smd roundrect
			(at 0.7 0)
			(size 0.8 1)
			(layers "F.Cu" "F.Mask" "F.Paste")
			(roundrect_rratio 0.2)
			(net 483 "Net-(D906-A)")
			(pinfunction "A")
			(pintype "passive")
		)
	)
	(footprint "antmicro-footprints:R_0402_1005Metric"
		(layer "F.Cu")
		(at 84.392962 154.8915 180)
		(descr "Resistor SMD 0402")
		(tags "resistor SMD 0402")
		(property "Reference" "R261"
			(at -3.615 -0.46 0)
			(layer "F.SilkS")
			(effects
				(font
					(size 0.7 0.7)
					(thickness 0.15)
				)
				(justify right bottom)
			)
		)
		(property "Value" "R_100k_0402"
			(at -1.011843 1.772047 0)
			(layer "F.Fab")
			(effects
				(font
					(size 0.7 0.7)
					(thickness 0.15)
				)
				(justify right bottom)
			)
		)
		(property "Datasheet" "https://www.bourns.com/docs/product-datasheets/cr.pdf"
			(at 0 0 180)
			(layer "F.Fab")
			(hide yes)
			(effects
				(font
					(size 1.27 1.27)
					(thickness 0.15)
				)
			)
		)
		(property "MPN" "CR0402-FX-1003GLF"
			(at 0 0 180)
			(unlocked yes)
			(layer "F.Fab")
			(hide yes)
			(effects
				(font
					(size 1 1)
					(thickness 0.15)
				)
			)
		)
		(property "Manufacturer" "Bourns"
			(at 0 0 180)
			(unlocked yes)
			(layer "F.Fab")
			(hide yes)
			(effects
				(font
					(size 1 1)
					(thickness 0.15)
				)
			)
		)
		(property "License" "Apache-2.0"
			(at 0 0 180)
			(unlocked yes)
			(layer "F.Fab")
			(hide yes)
			(effects
				(font
					(size 1 1)
					(thickness 0.15)
				)
			)
		)
		(property "Author" "Antmicro"
			(at 0 0 180)
			(unlocked yes)
			(layer "F.Fab")
			(hide yes)
			(effects
				(font
					(size 1 1)
					(thickness 0.15)
				)
			)
		)
		(property "Val" "100k"
			(at 0 0 180)
			(unlocked yes)
			(layer "F.Fab")
			(hide yes)
			(effects
				(font
					(size 1 1)
					(thickness 0.15)
				)
			)
		)
		(property "Tolerance" "1%"
			(at 0 0 180)
			(unlocked yes)
			(layer "F.Fab")
			(hide yes)
			(effects
				(font
					(size 1 1)
					(thickness 0.15)
				)
			)
		)
		(sheetname "/Compute module/")
		(sheetfile "compute-module.kicad_sch")
		(attr smd)
		(fp_rect
			(start -0.925 -0.47)
			(end 0.925 0.47)
			(stroke
				(width 0.05)
				(type default)
			)
			(fill no)
			(layer "F.CrtYd")
		)
		(fp_rect
			(start -0.5 -0.25)
			(end 0.5 0.25)
			(stroke
				(width 0.15)
				(type solid)
			)
			(fill no)
			(layer "F.Fab")
		)
		(fp_text user "Author: Antmicro"
			(at -0.95 4.169 180)
			(layer "F.Fab")
			(effects
				(font
					(size 0.7 0.7)
					(thickness 0.15)
				)
				(justify left bottom)
			)
		)
		(fp_text user "License: Apache-2.0"
			(at -0.95 5.169 180)
			(layer "F.Fab")
			(effects
				(font
					(size 0.7 0.7)
					(thickness 0.15)
				)
				(justify left bottom)
			)
		)
		(fp_text user "${REFERENCE}"
			(at -0.95 3.168 180)
			(layer "F.Fab")
			(effects
				(font
					(size 0.7 0.7)
					(thickness 0.15)
				)
				(justify left bottom)
			)
		)
		(pad "1" smd roundrect
			(at -0.48 0 180)
			(size 0.59 0.64)
			(layers "F.Cu" "F.Mask" "F.Paste")
			(roundrect_rratio 0.25)
			(net 444 "Net-(Q211-D)")
			(pintype "passive")
		)
		(pad "2" smd roundrect
			(at 0.48 0 180)
			(size 0.59 0.64)
			(layers "F.Cu" "F.Mask" "F.Paste")
			(roundrect_rratio 0.25)
			(net 24 "/Compute module/USBA_VBUS")
			(pintype "passive")
		)
	)
	(footprint "antmicro-footprints:Nexperia_DFN-10_2.5x1mm_P0.5mm"
		(layer "F.Cu")
		(at 142.292962 147.3665 90)
		(property "Reference" "D802"
			(at -7.17 0.305 90)
			(layer "F.SilkS")
			(effects
				(font
					(size 0.7 0.7)
					(thickness 0.15)
				)
				(justify left bottom)
			)
		)
		(property "Value" "PUSB3F96X_PASS"
			(at -0.016 1.705 90)
			(layer "F.Fab")
			(effects
				(font
					(size 0.7 0.7)
					(thickness 0.15)
				)
				(justify left bottom)
			)
		)
		(property "Datasheet" "https://mouser.com/datasheet/2/916/PUSB3F96-1600324.pdf"
			(at 0 0 90)
			(layer "F.Fab")
			(hide yes)
			(effects
				(font
					(size 1.27 1.27)
					(thickness 0.15)
				)
			)
		)
		(property "Manufacturer" "Nexperia"
			(at 0 0 90)
			(unlocked yes)
			(layer "F.Fab")
			(hide yes)
			(effects
				(font
					(size 1 1)
					(thickness 0.15)
				)
			)
		)
		(property "MPN" "PUSB3F96X"
			(at 0 0 90)
			(unlocked yes)
			(layer "F.Fab")
			(hide yes)
			(effects
				(font
					(size 1 1)
					(thickness 0.15)
				)
			)
		)
		(property "Author" "Antmicro"
			(at 0 0 90)
			(unlocked yes)
			(layer "F.Fab")
			(hide yes)
			(effects
				(font
					(size 1 1)
					(thickness 0.15)
				)
			)
		)
		(property "License" "Apache-2.0"
			(at 0 0 90)
			(unlocked yes)
			(layer "F.Fab")
			(hide yes)
			(effects
				(font
					(size 1 1)
					(thickness 0.15)
				)
			)
		)
		(sheetname "/Peripherals/")
		(sheetfile "peripherals.kicad_sch")
		(attr smd)
		(fp_line
			(start -1.375 -0.4)
			(end -1.375 0.4)
			(stroke
				(width 0.15)
				(type solid)
			)
			(layer "F.SilkS")
		)
		(fp_line
			(start 1.375 0.4)
			(end 1.375 -0.4)
			(stroke
				(width 0.15)
				(type solid)
			)
			(layer "F.SilkS")
		)
		(fp_circle
			(center -1.4 0.7)
			(end -1.349 0.7)
			(stroke
				(width 0.15)
				(type solid)
			)
			(fill yes)
			(layer "F.SilkS")
		)
		(fp_rect
			(start -1.4 -0.725)
			(end 1.4 0.725)
			(stroke
				(width 0.05)
				(type solid)
			)
			(fill no)
			(layer "F.CrtYd")
		)
		(fp_line
			(start 1.25 -0.5)
			(end -1.25 -0.5)
			(stroke
				(width 0.15)
				(type solid)
			)
			(layer "F.Fab")
		)
		(fp_line
			(start -1.25 -0.5)
			(end -1.25 0.15)
			(stroke
				(width 0.15)
				(type solid)
			)
			(layer "F.Fab")
		)
		(fp_line
			(start -1.25 0.15)
			(end -0.9 0.5)
			(stroke
				(width 0.15)
				(type solid)
			)
			(layer "F.Fab")
		)
		(fp_line
			(start 1.25 0.5)
			(end 1.25 -0.5)
			(stroke
				(width 0.15)
				(type solid)
			)
			(layer "F.Fab")
		)
		(fp_line
			(start -0.9 0.5)
			(end 1.25 0.5)
			(stroke
				(width 0.15)
				(type solid)
			)
			(layer "F.Fab")
		)
		(fp_text user "Author: Antmicro"
			(at -1.367 4.905 90)
			(layer "F.Fab")
			(effects
				(font
					(size 0.7 0.7)
					(thickness 0.15)
				)
				(justify left bottom)
			)
		)
		(fp_text user "License: Apache-2.0"
			(at -1.367 6.105 90)
			(layer "F.Fab")
			(effects
				(font
					(size 0.7 0.7)
					(thickness 0.15)
				)
				(justify left bottom)
			)
		)
		(fp_text user "${REFERENCE}"
			(at -1.367 3.704 90)
			(layer "F.Fab")
			(effects
				(font
					(size 0.7 0.7)
					(thickness 0.15)
				)
				(justify left bottom)
			)
		)
		(pad "1" smd rect
			(at -1 0.3875 90)
			(size 0.2 0.475)
			(layers "F.Cu" "F.Mask" "F.Paste")
			(net 238 "/Compute module/GPIO.17")
			(pinfunction "CH1")
			(pintype "passive")
			(solder_mask_margin 0.05)
		)
		(pad "2" smd rect
			(at -0.5 0.3875 90)
			(size 0.2 0.475)
			(layers "F.Cu" "F.Mask" "F.Paste")
			(net 236 "/Compute module/GPIO.27")
			(pinfunction "CH2")
			(pintype "passive")
			(solder_mask_margin 0.05)
		)
		(pad "3" smd rect
			(at 0 0.3875 90)
			(size 0.2 0.475)
			(layers "F.Cu" "F.Mask" "F.Paste")
			(net 3 "GND")
			(pinfunction "GND")
			(pintype "passive")
			(solder_mask_margin 0.05)
		)
		(pad "4" smd rect
			(at 0.5 0.3875 90)
			(size 0.2 0.475)
			(layers "F.Cu" "F.Mask" "F.Paste")
			(net 234 "/Compute module/GPIO.22")
			(pinfunction "CH3")
			(pintype "passive")
			(solder_mask_margin 0.05)
		)
		(pad "5" smd rect
			(at 1 0.3875 90)
			(size 0.2 0.475)
			(layers "F.Cu" "F.Mask" "F.Paste")
			(net 232 "/Compute module/GPIO.10")
			(pinfunction "CH4")
			(pintype "passive")
			(solder_mask_margin 0.05)
		)
		(pad "6" smd rect
			(at 1 -0.3875 90)
			(size 0.2 0.475)
			(layers "F.Cu" "F.Mask" "F.Paste")
			(net 232 "/Compute module/GPIO.10")
			(pinfunction "CH4")
			(pintype "passive")
			(solder_mask_margin 0.05)
		)
		(pad "7" smd rect
			(at 0.5 -0.3875 90)
			(size 0.2 0.475)
			(layers "F.Cu" "F.Mask" "F.Paste")
			(net 234 "/Compute module/GPIO.22")
			(pinfunction "CH3")
			(pintype "passive")
			(solder_mask_margin 0.05)
		)
		(pad "8" smd rect
			(at 0 -0.3875 90)
			(size 0.2 0.475)
			(layers "F.Cu" "F.Mask" "F.Paste")
			(net 3 "GND")
			(pinfunction "GND")
			(pintype "passive")
			(solder_mask_margin 0.05)
		)
		(pad "9" smd rect
			(at -0.501 -0.3875 90)
			(size 0.2 0.475)
			(layers "F.Cu" "F.Mask" "F.Paste")
			(net 236 "/Compute module/GPIO.27")
			(pinfunction "CH2")
			(pintype "passive")
			(solder_mask_margin 0.05)
		)
		(pad "10" smd rect
			(at -1 -0.3875 90)
			(size 0.2 0.475)
			(layers "F.Cu" "F.Mask" "F.Paste")
			(net 238 "/Compute module/GPIO.17")
			(pinfunction "CH1")
			(pintype "passive")
			(solder_mask_margin 0.05)
		)
	)
	(footprint "antmicro-footprints:R_0402_1005Metric"
		(layer "F.Cu")
		(at 120.3 157.0415 180)
		(descr "Resistor SMD 0402")
		(tags "resistor SMD 0402")
		(property "Reference" "R222"
			(at -4.3 -0.175 180)
			(layer "F.SilkS")
			(effects
				(font
					(size 0.7 0.7)
					(thickness 0.15)
				)
				(justify left bottom)
			)
		)
		(property "Value" "R_0R_0402"
			(at -1.011843 1.772047 180)
			(layer "F.Fab")
			(effects
				(font
					(size 0.7 0.7)
					(thickness 0.15)
				)
				(justify left bottom)
			)
		)
		(property "Datasheet" "https://industrial.panasonic.com/cdbs/www-data/pdf/RDA0000/AOA0000C301.pdf"
			(at 0 0 180)
			(layer "F.Fab")
			(hide yes)
			(effects
				(font
					(size 1.27 1.27)
					(thickness 0.15)
				)
			)
		)
		(property "Manufacturer" "Panasonic"
			(at 0 0 180)
			(unlocked yes)
			(layer "F.Fab")
			(hide yes)
			(effects
				(font
					(size 1 1)
					(thickness 0.15)
				)
			)
		)
		(property "MPN" "ERJ2GE0R00X"
			(at 0 0 180)
			(unlocked yes)
			(layer "F.Fab")
			(hide yes)
			(effects
				(font
					(size 1 1)
					(thickness 0.15)
				)
			)
		)
		(property "Val" "0R"
			(at 0 0 180)
			(unlocked yes)
			(layer "F.Fab")
			(hide yes)
			(effects
				(font
					(size 1 1)
					(thickness 0.15)
				)
			)
		)
		(property "License" "Apache-2.0"
			(at 0 0 180)
			(unlocked yes)
			(layer "F.Fab")
			(hide yes)
			(effects
				(font
					(size 1 1)
					(thickness 0.15)
				)
			)
		)
		(property "Author" "Antmicro"
			(at 0 0 180)
			(unlocked yes)
			(layer "F.Fab")
			(hide yes)
			(effects
				(font
					(size 1 1)
					(thickness 0.15)
				)
			)
		)
		(property "Tolerance" "~"
			(at 0 0 180)
			(unlocked yes)
			(layer "F.Fab")
			(hide yes)
			(effects
				(font
					(size 1 1)
					(thickness 0.15)
				)
			)
		)
		(property "Current" "1A"
			(at 0 0 180)
			(unlocked yes)
			(layer "F.Fab")
			(hide yes)
			(effects
				(font
					(size 1 1)
					(thickness 0.15)
				)
			)
		)
		(sheetname "/Compute module/")
		(sheetfile "compute-module.kicad_sch")
		(attr smd)
		(fp_rect
			(start -0.925 -0.47)
			(end 0.925 0.47)
			(stroke
				(width 0.05)
				(type default)
			)
			(fill no)
			(layer "F.CrtYd")
		)
		(fp_rect
			(start -0.5 -0.25)
			(end 0.5 0.25)
			(stroke
				(width 0.15)
				(type solid)
			)
			(fill no)
			(layer "F.Fab")
		)
		(fp_text user "License: Apache-2.0"
			(at -0.95 5.169 180)
			(layer "F.Fab")
			(effects
				(font
					(size 0.7 0.7)
					(thickness 0.15)
				)
				(justify left bottom)
			)
		)
		(fp_text user "Author: Antmicro"
			(at -0.95 4.169 180)
			(layer "F.Fab")
			(effects
				(font
					(size 0.7 0.7)
					(thickness 0.15)
				)
				(justify left bottom)
			)
		)
		(fp_text user "${REFERENCE}"
			(at -0.95 3.168 180)
			(layer "F.Fab")
			(effects
				(font
					(size 0.7 0.7)
					(thickness 0.15)
				)
				(justify left bottom)
			)
		)
		(pad "1" smd roundrect
			(at -0.48 0 180)
			(size 0.59 0.64)
			(layers "F.Cu" "F.Mask" "F.Paste")
			(roundrect_rratio 0.25)
			(net 159 "/Compute module/NVMe.RX3_P")
			(pintype "passive")
		)
		(pad "2" smd roundrect
			(at 0.48 0 180)
			(size 0.59 0.64)
			(layers "F.Cu" "F.Mask" "F.Paste")
			(roundrect_rratio 0.25)
			(net 154 "/Compute module/R3_P")
			(pintype "passive")
		)
	)
)
